(kicad_pcb
	(version 20260206)
	(generator "pcbnew")
	(generator_version "10.0")
	(general
		(thickness 1.6)
		(legacy_teardrops no)
	)
	(paper "A4")
	(title_block
		(title "01162023_DA0F0TEBIF0_F0T_Expander_BD_F_brd_V02_OCP.brd")
		(comment 1 "Grand Teton / footprints 8941-8948 of 9728")
	)
	(layers
		(0 "F.Cu" signal "TOP")
		(4 "In1.Cu" signal "GND")
		(6 "In2.Cu" signal "VCC")
		(8 "In3.Cu" signal "VCC1")
		(10 "In4.Cu" signal "GND1")
		(12 "In5.Cu" signal "IN1")
		(14 "In6.Cu" signal "GND2")
		(16 "In7.Cu" signal "IN2")
		(18 "In8.Cu" signal "GND3")
		(20 "In9.Cu" signal "IN3")
		(22 "In10.Cu" signal "GND4")
		(24 "In11.Cu" signal "IN4")
		(26 "In12.Cu" signal "GND5")
		(28 "In13.Cu" signal "IN5")
		(30 "In14.Cu" signal "GND6")
		(32 "In15.Cu" signal "IN6")
		(34 "In16.Cu" signal "GND7")
		(2 "B.Cu" signal "BOTTOM")
		(9 "F.Adhes" user "F.Adhesive")
		(11 "B.Adhes" user "B.Adhesive")
		(13 "F.Paste" user "Package Geometry/Pastemask Top")
		(15 "B.Paste" user "Package Geometry/Pastemask Bottom")
		(5 "F.SilkS" user "Ref Des/Silkscreen Top")
		(7 "B.SilkS" user "Ref Des/Silkscreen Bottom")
		(1 "F.Mask" user "Board Geometry/Soldermask Top")
		(3 "B.Mask" user "Board Geometry/Soldermask Bottom")
		(17 "Dwgs.User" user "User.Drawings")
		(19 "Cmts.User" user "User.Comments")
		(21 "Eco1.User" user "User.Eco1")
		(23 "Eco2.User" user "User.Eco2")
		(25 "Edge.Cuts" user "Board Geometry/Outline")
		(27 "Margin" user)
		(31 "F.CrtYd" user "Package Geometry/Place Bound Top")
		(29 "B.CrtYd" user "Package Geometry/Place Bound Bottom")
		(35 "F.Fab" user "Ref Des/Assembly Top")
		(33 "B.Fab" user "Ref Des/Assembly Bottom")
	)
	(footprint ""
		(layer "B.Cu")
		(at 342.894158 -217.187018 -90)
		(property "Reference" "C2060"
			(at 0 0 90)
			(layer "B.SilkS")
			(hide yes)
			(effects
				(font
					(size 1.27 1.27)
				)
				(justify mirror)
			)
		)
		(property "Value" ""
			(at 0 0 90)
			(layer "B.Fab")
			(effects
				(font
					(size 1.27 1.27)
				)
				(justify mirror)
			)
		)
		(duplicate_pad_numbers_are_jumpers no)
		(fp_line
			(start -0.69215 0.2921)
			(end 0.69215 0.2921)
			(stroke
				(width 0.1524)
				(type default)
			)
			(layer "B.SilkS")
		)
		(fp_line
			(start 0.69215 0.2921)
			(end 0.69215 -0.2921)
			(stroke
				(width 0.1524)
				(type default)
			)
			(layer "B.SilkS")
		)
		(fp_line
			(start -0.69215 -0.2921)
			(end -0.69215 0.2921)
			(stroke
				(width 0.1524)
				(type default)
			)
			(layer "B.SilkS")
		)
		(fp_line
			(start 0.69215 -0.2921)
			(end -0.69215 -0.2921)
			(stroke
				(width 0.1524)
				(type default)
			)
			(layer "B.SilkS")
		)
		(fp_line
			(start -0.51435 0.2794)
			(end 0.51435 0.2794)
			(stroke
				(width 0.1)
				(type default)
			)
			(layer "B.Fab")
		)
		(fp_line
			(start 0.51435 0.2794)
			(end 0.51435 -0.2794)
			(stroke
				(width 0.1)
				(type default)
			)
			(layer "B.Fab")
		)
		(fp_line
			(start -0.51435 -0.2794)
			(end -0.51435 0.2794)
			(stroke
				(width 0.1)
				(type default)
			)
			(layer "B.Fab")
		)
		(fp_line
			(start 0.51435 -0.2794)
			(end -0.51435 -0.2794)
			(stroke
				(width 0.1)
				(type default)
			)
			(layer "B.Fab")
		)
		(pad "1" smd circle
			(at 0.40005 0 90)
			(size 0 0)
			(layers "B.Cu" "B.Mask" "B.Paste")
			(net "P3V3_FPGA_VCCIO2")
		)
		(pad "2" smd circle
			(at -0.40005 0 90)
			(size 0 0)
			(layers "B.Cu" "B.Mask" "B.Paste")
			(net "GND")
		)
		(zone
			(layer "B.Cu")
			(hatch none 0.5)
			(connect_pads
				(clearance 0)
			)
			(min_thickness 0.25)
			(keepout
				(tracks not_allowed)
				(vias allowed)
				(pads allowed)
				(copperpour not_allowed)
				(footprints allowed)
			)
			(placement
				(enabled no)
				(sheetname "")
			)
			(fill
				(thermal_gap 0.5)
				(thermal_bridge_width 0.5)
				(island_removal_mode 0)
			)
			(polygon
				(pts
					(xy 342.806528 -216.996518) (xy 342.748362 -217.087958) (xy 342.748362 -217.287348) (xy 342.806528 -217.377518)
					(xy 342.981788 -217.377518) (xy 343.040208 -217.287348) (xy 343.040208 -217.087958) (xy 342.982042 -216.996518)
				)
			)
		)
	)
	(footprint ""
		(layer "B.Cu")
		(at 386.842 -243.205 -90)
		(property "Reference" "U102"
			(at -0.005334 1.827276 270)
			(unlocked yes)
			(layer "B.SilkS")
			(effects
				(font
					(size 0.7874 0.5842)
					(thickness 0.1524)
				)
				(justify mirror)
			)
		)
		(property "Value" ""
			(at 0 0 90)
			(layer "B.Fab")
			(effects
				(font
					(size 1.27 1.27)
				)
				(justify mirror)
			)
		)
		(duplicate_pad_numbers_are_jumpers no)
		(fp_line
			(start -1.7272 1.1176)
			(end 1.7272 1.1176)
			(stroke
				(width 0.1524)
				(type default)
			)
			(layer "B.SilkS")
		)
		(fp_line
			(start 1.7272 1.1176)
			(end 1.7272 -1.1176)
			(stroke
				(width 0.1524)
				(type default)
			)
			(layer "B.SilkS")
		)
		(fp_line
			(start 0 -0.7366)
			(end 0.254 -1.1176)
			(stroke
				(width 0.1524)
				(type default)
			)
			(layer "B.SilkS")
		)
		(fp_line
			(start -1.7272 -1.1176)
			(end -1.7272 1.1176)
			(stroke
				(width 0.1524)
				(type default)
			)
			(layer "B.SilkS")
		)
		(fp_line
			(start -1.7272 -1.1176)
			(end -0.254 -1.1176)
			(stroke
				(width 0.1524)
				(type default)
			)
			(layer "B.SilkS")
		)
		(fp_line
			(start -0.254 -1.1176)
			(end 0 -0.7366)
			(stroke
				(width 0.1524)
				(type default)
			)
			(layer "B.SilkS")
		)
		(fp_line
			(start 0.254 -1.1176)
			(end 1.7272 -1.1176)
			(stroke
				(width 0.1524)
				(type default)
			)
			(layer "B.SilkS")
		)
		(fp_poly
			(pts
				(xy 1.9558 -0.649986) (xy 2.7178 -0.268986) (xy 2.7178 -1.030986)
			)
			(stroke
				(width 0)
				(type default)
			)
			(fill yes)
			(layer "B.SilkS")
		)
		(fp_line
			(start -1.5748 1.1176)
			(end -1.5748 -1.1176)
			(stroke
				(width 0.1)
				(type default)
			)
			(layer "B.Fab")
		)
		(fp_line
			(start 1.5748 1.1176)
			(end -1.5748 1.1176)
			(stroke
				(width 0.1)
				(type default)
			)
			(layer "B.Fab")
		)
		(fp_line
			(start -1.5748 -1.1176)
			(end 1.5748 -1.1176)
			(stroke
				(width 0.1)
				(type default)
			)
			(layer "B.Fab")
		)
		(fp_line
			(start 1.5748 -1.1176)
			(end 1.5748 1.1176)
			(stroke
				(width 0.1)
				(type default)
			)
			(layer "B.Fab")
		)
		(fp_poly
			(pts
				(xy 1.9558 -0.649986) (xy 2.7178 -0.268986) (xy 2.7178 -1.030986)
			)
			(stroke
				(width 0)
				(type default)
			)
			(fill yes)
			(layer "B.Fab")
		)
		(pad "1" smd rect
			(at 0.999998 -0.649986 180)
			(size 0.3556 1.1176)
			(layers "B.Cu" "B.Mask" "B.Paste")
			(net "UART_PEX2_SDB_R_RX")
		)
		(pad "2" smd rect
			(at 0.999998 0 180)
			(size 0.3556 1.1176)
			(layers "B.Cu" "B.Mask" "B.Paste")
			(net "GND")
		)
		(pad "3" smd rect
			(at 0.999998 0.649986 180)
			(size 0.3556 1.1176)
			(layers "B.Cu" "B.Mask" "B.Paste")
			(net "UART_PEX3_SDB_R_RX")
		)
		(pad "4" smd rect
			(at -0.999998 0.649986 180)
			(size 0.3556 1.1176)
			(layers "B.Cu" "B.Mask" "B.Paste")
			(net "UART_PEX3_SDB_BUF_R_RX")
		)
		(pad "5" smd rect
			(at -0.999998 0 180)
			(size 0.3556 1.1176)
			(layers "B.Cu" "B.Mask" "B.Paste")
			(net "P3V3_AUX")
		)
		(pad "6" smd rect
			(at -0.999998 -0.649986 180)
			(size 0.3556 1.1176)
			(layers "B.Cu" "B.Mask" "B.Paste")
			(net "UART_PEX2_SDB_BUF_R_RX")
		)
	)
	(footprint ""
		(layer "B.Cu")
		(at 133.538214 -208.952846 90)
		(property "Reference" "C2603"
			(at 0 0 90)
			(layer "B.SilkS")
			(hide yes)
			(effects
				(font
					(size 1.27 1.27)
				)
				(justify mirror)
			)
		)
		(property "Value" ""
			(at 0 0 90)
			(layer "B.Fab")
			(effects
				(font
					(size 1.27 1.27)
				)
				(justify mirror)
			)
		)
		(duplicate_pad_numbers_are_jumpers no)
		(fp_line
			(start 0.7874 -0.4064)
			(end -0.7874 -0.4064)
			(stroke
				(width 0.1524)
				(type default)
			)
			(layer "B.SilkS")
		)
		(fp_line
			(start -0.7874 -0.4064)
			(end -0.7874 0.4064)
			(stroke
				(width 0.1524)
				(type default)
			)
			(layer "B.SilkS")
		)
		(fp_line
			(start 0.7874 0.4064)
			(end 0.7874 -0.4064)
			(stroke
				(width 0.1524)
				(type default)
			)
			(layer "B.SilkS")
		)
		(fp_line
			(start -0.7874 0.4064)
			(end 0.7874 0.4064)
			(stroke
				(width 0.1524)
				(type default)
			)
			(layer "B.SilkS")
		)
		(fp_line
			(start 0.67945 -0.305054)
			(end 0.12065 -0.305054)
			(stroke
				(width 0.1)
				(type default)
			)
			(layer "B.Fab")
		)
		(fp_line
			(start 0.12065 -0.305054)
			(end 0.12065 -0.2794)
			(stroke
				(width 0.1)
				(type default)
			)
			(layer "B.Fab")
		)
		(fp_line
			(start -0.12065 -0.3048)
			(end -0.67945 -0.3048)
			(stroke
				(width 0.1)
				(type default)
			)
			(layer "B.Fab")
		)
		(fp_line
			(start -0.67945 -0.3048)
			(end -0.67945 0.3048)
			(stroke
				(width 0.1)
				(type default)
			)
			(layer "B.Fab")
		)
		(fp_line
			(start 0.12065 -0.2794)
			(end -0.12065 -0.2794)
			(stroke
				(width 0.1)
				(type default)
			)
			(layer "B.Fab")
		)
		(fp_line
			(start -0.12065 -0.2794)
			(end -0.12065 -0.3048)
			(stroke
				(width 0.1)
				(type default)
			)
			(layer "B.Fab")
		)
		(fp_line
			(start 0.12065 0.2794)
			(end 0.12065 0.3048)
			(stroke
				(width 0.1)
				(type default)
			)
			(layer "B.Fab")
		)
		(fp_line
			(start -0.120396 0.2794)
			(end 0.12065 0.2794)
			(stroke
				(width 0.1)
				(type default)
			)
			(layer "B.Fab")
		)
		(fp_line
			(start 0.67945 0.3048)
			(end 0.67945 -0.305054)
			(stroke
				(width 0.1)
				(type default)
			)
			(layer "B.Fab")
		)
		(fp_line
			(start 0.12065 0.3048)
			(end 0.67945 0.3048)
			(stroke
				(width 0.1)
				(type default)
			)
			(layer "B.Fab")
		)
		(fp_line
			(start -0.120396 0.3048)
			(end -0.120396 0.2794)
			(stroke
				(width 0.1)
				(type default)
			)
			(layer "B.Fab")
		)
		(fp_line
			(start -0.67945 0.3048)
			(end -0.120396 0.3048)
			(stroke
				(width 0.1)
				(type default)
			)
			(layer "B.Fab")
		)
		(pad "1" smd circle
			(at 0.40005 0 270)
			(size 0 0)
			(layers "B.Cu" "B.Mask" "B.Paste")
			(net "P3V3_AUX")
		)
		(pad "2" smd circle
			(at -0.40005 0 270)
			(size 0 0)
			(layers "B.Cu" "B.Mask" "B.Paste")
			(net "GND")
		)
	)
	(footprint ""
		(layer "B.Cu")
		(at 278.064214 -142.795752 180)
		(property "Reference" "C907"
			(at 0 0 0)
			(layer "B.SilkS")
			(hide yes)
			(effects
				(font
					(size 1.27 1.27)
				)
				(justify mirror)
			)
		)
		(property "Value" ""
			(at 0 0 0)
			(layer "B.Fab")
			(effects
				(font
					(size 1.27 1.27)
				)
				(justify mirror)
			)
		)
		(duplicate_pad_numbers_are_jumpers no)
		(fp_line
			(start 0.299974 0.150114)
			(end 0.299974 -0.150114)
			(stroke
				(width 0.1)
				(type default)
			)
			(layer "B.Fab")
		)
		(fp_line
			(start 0.299974 -0.150114)
			(end -0.299974 -0.150114)
			(stroke
				(width 0.1)
				(type default)
			)
			(layer "B.Fab")
		)
		(fp_line
			(start -0.299974 0.150114)
			(end 0.299974 0.150114)
			(stroke
				(width 0.1)
				(type default)
			)
			(layer "B.Fab")
		)
		(fp_line
			(start -0.299974 -0.150114)
			(end -0.299974 0.150114)
			(stroke
				(width 0.1)
				(type default)
			)
			(layer "B.Fab")
		)
		(pad "1" smd rect
			(at 0.2667 0)
			(size 0.3048 0.381)
			(layers "B.Cu" "B.Mask" "B.Paste")
			(net "P12V_NIC4")
		)
		(pad "2" smd rect
			(at -0.2667 0)
			(size 0.3048 0.381)
			(layers "B.Cu" "B.Mask" "B.Paste")
			(net "GND")
		)
	)
	(footprint ""
		(layer "B.Cu")
		(at 170.999912 -301.599854 -90)
		(property "Reference" "C1466"
			(at 0 0 90)
			(layer "B.SilkS")
			(hide yes)
			(effects
				(font
					(size 1.27 1.27)
				)
				(justify mirror)
			)
		)
		(property "Value" ""
			(at 0 0 90)
			(layer "B.Fab")
			(effects
				(font
					(size 1.27 1.27)
				)
				(justify mirror)
			)
		)
		(duplicate_pad_numbers_are_jumpers no)
		(fp_line
			(start -0.299974 0.150114)
			(end 0.299974 0.150114)
			(stroke
				(width 0.1)
				(type default)
			)
			(layer "B.Fab")
		)
		(fp_line
			(start 0.299974 0.150114)
			(end 0.299974 -0.150114)
			(stroke
				(width 0.1)
				(type default)
			)
			(layer "B.Fab")
		)
		(fp_line
			(start -0.299974 -0.150114)
			(end -0.299974 0.150114)
			(stroke
				(width 0.1)
				(type default)
			)
			(layer "B.Fab")
		)
		(fp_line
			(start 0.299974 -0.150114)
			(end -0.299974 -0.150114)
			(stroke
				(width 0.1)
				(type default)
			)
			(layer "B.Fab")
		)
		(pad "1" smd rect
			(at 0.2667 0 90)
			(size 0.3048 0.381)
			(layers "B.Cu" "B.Mask" "B.Paste")
			(net "P0V8_SERDES_VDDA_PEX1")
		)
		(pad "2" smd rect
			(at -0.2667 0 90)
			(size 0.3048 0.381)
			(layers "B.Cu" "B.Mask" "B.Paste")
			(net "GND")
		)
	)
	(footprint ""
		(layer "B.Cu")
		(at 56.799988 -301.599854 -90)
		(property "Reference" "C1198"
			(at 0 0 90)
			(layer "B.SilkS")
			(hide yes)
			(effects
				(font
					(size 1.27 1.27)
				)
				(justify mirror)
			)
		)
		(property "Value" ""
			(at 0 0 90)
			(layer "B.Fab")
			(effects
				(font
					(size 1.27 1.27)
				)
				(justify mirror)
			)
		)
		(duplicate_pad_numbers_are_jumpers no)
		(fp_line
			(start -0.299974 0.150114)
			(end 0.299974 0.150114)
			(stroke
				(width 0.1)
				(type default)
			)
			(layer "B.Fab")
		)
		(fp_line
			(start 0.299974 0.150114)
			(end 0.299974 -0.150114)
			(stroke
				(width 0.1)
				(type default)
			)
			(layer "B.Fab")
		)
		(fp_line
			(start -0.299974 -0.150114)
			(end -0.299974 0.150114)
			(stroke
				(width 0.1)
				(type default)
			)
			(layer "B.Fab")
		)
		(fp_line
			(start 0.299974 -0.150114)
			(end -0.299974 -0.150114)
			(stroke
				(width 0.1)
				(type default)
			)
			(layer "B.Fab")
		)
		(pad "1" smd rect
			(at 0.2667 0 90)
			(size 0.3048 0.381)
			(layers "B.Cu" "B.Mask" "B.Paste")
			(net "P0V8_SERDES_VDDA_PEX0")
		)
		(pad "2" smd rect
			(at -0.2667 0 90)
			(size 0.3048 0.381)
			(layers "B.Cu" "B.Mask" "B.Paste")
			(net "GND")
		)
	)
	(footprint ""
		(layer "B.Cu")
		(at 366.439196 -282.040584 90)
		(property "Reference" "PR162"
			(at 0 0 90)
			(layer "B.SilkS")
			(hide yes)
			(effects
				(font
					(size 1.27 1.27)
				)
				(justify mirror)
			)
		)
		(property "Value" ""
			(at 0 0 90)
			(layer "B.Fab")
			(effects
				(font
					(size 1.27 1.27)
				)
				(justify mirror)
			)
		)
		(duplicate_pad_numbers_are_jumpers no)
		(fp_line
			(start 0.7874 -0.4064)
			(end -0.7874 -0.4064)
			(stroke
				(width 0.1524)
				(type default)
			)
			(layer "B.SilkS")
		)
		(fp_line
			(start -0.7874 -0.4064)
			(end -0.7874 0.4064)
			(stroke
				(width 0.1524)
				(type default)
			)
			(layer "B.SilkS")
		)
		(fp_line
			(start 0.7874 0.4064)
			(end 0.7874 -0.4064)
			(stroke
				(width 0.1524)
				(type default)
			)
			(layer "B.SilkS")
		)
		(fp_line
			(start -0.7874 0.4064)
			(end 0.7874 0.4064)
			(stroke
				(width 0.1524)
				(type default)
			)
			(layer "B.SilkS")
		)
		(fp_line
			(start 0.67945 -0.305054)
			(end 0.12065 -0.305054)
			(stroke
				(width 0.1)
				(type default)
			)
			(layer "B.Fab")
		)
		(fp_line
			(start 0.12065 -0.305054)
			(end 0.12065 -0.2794)
			(stroke
				(width 0.1)
				(type default)
			)
			(layer "B.Fab")
		)
		(fp_line
			(start -0.12065 -0.3048)
			(end -0.67945 -0.3048)
			(stroke
				(width 0.1)
				(type default)
			)
			(layer "B.Fab")
		)
		(fp_line
			(start -0.67945 -0.3048)
			(end -0.67945 0.3048)
			(stroke
				(width 0.1)
				(type default)
			)
			(layer "B.Fab")
		)
		(fp_line
			(start 0.12065 -0.2794)
			(end -0.12065 -0.2794)
			(stroke
				(width 0.1)
				(type default)
			)
			(layer "B.Fab")
		)
		(fp_line
			(start -0.12065 -0.2794)
			(end -0.12065 -0.3048)
			(stroke
				(width 0.1)
				(type default)
			)
			(layer "B.Fab")
		)
		(fp_line
			(start 0.12065 0.2794)
			(end 0.12065 0.3048)
			(stroke
				(width 0.1)
				(type default)
			)
			(layer "B.Fab")
		)
		(fp_line
			(start -0.120396 0.2794)
			(end 0.12065 0.2794)
			(stroke
				(width 0.1)
				(type default)
			)
			(layer "B.Fab")
		)
		(fp_line
			(start 0.67945 0.3048)
			(end 0.67945 -0.305054)
			(stroke
				(width 0.1)
				(type default)
			)
			(layer "B.Fab")
		)
		(fp_line
			(start 0.12065 0.3048)
			(end 0.67945 0.3048)
			(stroke
				(width 0.1)
				(type default)
			)
			(layer "B.Fab")
		)
		(fp_line
			(start -0.120396 0.3048)
			(end -0.120396 0.2794)
			(stroke
				(width 0.1)
				(type default)
			)
			(layer "B.Fab")
		)
		(fp_line
			(start -0.67945 0.3048)
			(end -0.120396 0.3048)
			(stroke
				(width 0.1)
				(type default)
			)
			(layer "B.Fab")
		)
		(pad "1" smd circle
			(at 0.40005 0 270)
			(size 0 0)
			(layers "B.Cu" "B.Mask" "B.Paste")
			(net "SW_P0V8_PEX3_VOS2")
		)
		(pad "2" smd circle
			(at -0.40005 0 270)
			(size 0 0)
			(layers "B.Cu" "B.Mask" "B.Paste")
			(net "P0V8_PEX3")
		)
	)
	(footprint ""
		(layer "B.Cu")
		(at 294.380158 -295.221914)
		(property "Reference" "C1612"
			(at 0 0 0)
			(layer "B.SilkS")
			(hide yes)
			(effects
				(font
					(size 1.27 1.27)
				)
				(justify mirror)
			)
		)
		(property "Value" ""
			(at 0 0 0)
			(layer "B.Fab")
			(effects
				(font
					(size 1.27 1.27)
				)
				(justify mirror)
			)
		)
		(duplicate_pad_numbers_are_jumpers no)
		(fp_line
			(start -1.2954 -0.5842)
			(end -1.2954 0.5842)
			(stroke
				(width 0.1524)
				(type default)
			)
			(layer "B.SilkS")
		)
		(fp_line
			(start -1.2954 0.5842)
			(end 1.2954 0.5842)
			(stroke
				(width 0.1524)
				(type default)
			)
			(layer "B.SilkS")
		)
		(fp_line
			(start 1.2954 -0.5842)
			(end -1.2954 -0.5842)
			(stroke
				(width 0.1524)
				(type default)
			)
			(layer "B.SilkS")
		)
		(fp_line
			(start 1.2954 0.5842)
			(end 1.2954 -0.5842)
			(stroke
				(width 0.1524)
				(type default)
			)
			(layer "B.SilkS")
		)
		(fp_line
			(start -1.1938 -0.4064)
			(end -1.1938 0.4064)
			(stroke
				(width 0.1)
				(type default)
			)
			(layer "B.Fab")
		)
		(fp_line
			(start -1.1938 0.4064)
			(end -0.8636 0.4064)
			(stroke
				(width 0.1)
				(type default)
			)
			(layer "B.Fab")
		)
		(fp_line
			(start -0.8636 -0.4572)
			(end -0.8636 -0.4064)
			(stroke
				(width 0.1)
				(type default)
			)
			(layer "B.Fab")
		)
		(fp_line
			(start -0.8636 -0.4064)
			(end -1.1938 -0.4064)
			(stroke
				(width 0.1)
				(type default)
			)
			(layer "B.Fab")
		)
		(fp_line
			(start -0.8636 0.4064)
			(end -0.8636 0.4572)
			(stroke
				(width 0.1)
				(type default)
			)
			(layer "B.Fab")
		)
		(fp_line
			(start -0.8636 0.4572)
			(end 0.8636 0.4572)
			(stroke
				(width 0.1)
				(type default)
			)
			(layer "B.Fab")
		)
		(fp_line
			(start 0.8636 -0.4572)
			(end -0.8636 -0.4572)
			(stroke
				(width 0.1)
				(type default)
			)
			(layer "B.Fab")
		)
		(fp_line
			(start 0.8636 -0.4064)
			(end 0.8636 -0.4572)
			(stroke
				(width 0.1)
				(type default)
			)
			(layer "B.Fab")
		)
		(fp_line
			(start 0.8636 0.4064)
			(end 1.1938 0.4064)
			(stroke
				(width 0.1)
				(type default)
			)
			(layer "B.Fab")
		)
		(fp_line
			(start 0.8636 0.4572)
			(end 0.8636 0.4064)
			(stroke
				(width 0.1)
				(type default)
			)
			(layer "B.Fab")
		)
		(fp_line
			(start 1.1938 -0.4064)
			(end 0.8636 -0.4064)
			(stroke
				(width 0.1)
				(type default)
			)
			(layer "B.Fab")
		)
		(fp_line
			(start 1.1938 0.4064)
			(end 1.1938 -0.4064)
			(stroke
				(width 0.1)
				(type default)
			)
			(layer "B.Fab")
		)
		(pad "1" smd rect
			(at 0.7366 0 270)
			(size 0.7112 0.8128)
			(layers "B.Cu" "B.Mask" "B.Paste")
			(net "P0V8_PEX2")
		)
		(pad "2" smd rect
			(at -0.7366 0 270)
			(size 0.7112 0.8128)
			(layers "B.Cu" "B.Mask" "B.Paste")
			(net "GND")
		)
	)
)
